# S9S_MB_2U (Grand Teton) — schematic netlist excerpt (pin names and nets, part order shuffled) for the footprints in the layout excerpt that follows; sources: Cadence DE-HDL packaged netlist, KiCad conversion of 03242023_DA0F0TMBIJ0_F0T_Motherboard_J_brd_V01_OCP.brd

R4463  Q_RES  680 1% EMPTY  pkg 0402LF  page 196 : A = USB_HUB_2_RREF ; B = GND
R4051  Q_RES  33.2 1% CHIP  pkg 0402LF  page 225 : A = H_CPU_ERR1_LVC2_R_N ; B = H_CPU_ERR1_LVC2_N

(kicad_pcb
	(version 20260206)
	(generator "pcbnew")
	(generator_version "10.0")
	(general
		(thickness 1.6)
		(legacy_teardrops no)
	)
	(paper "A4")
	(title_block
		(title "03242023_DA0F0TMBIJ0_F0T_Motherboard_J_brd_V01_OCP.brd")
		(comment 1 "Grand Teton / footprints 273-274 of 6105")
	)
	(layers
		(0 "F.Cu" signal "TOP")
		(4 "In1.Cu" signal "GND")
		(6 "In2.Cu" signal "IN1")
		(8 "In3.Cu" signal "GND1")
		(10 "In4.Cu" signal "IN2")
		(12 "In5.Cu" signal "GND2")
		(14 "In6.Cu" signal "IN3")
		(16 "In7.Cu" signal "GND3")
		(18 "In8.Cu" signal "VCC")
		(20 "In9.Cu" signal "VCC1")
		(22 "In10.Cu" signal "GND4")
		(24 "In11.Cu" signal "IN4")
		(26 "In12.Cu" signal "GND5")
		(28 "In13.Cu" signal "IN5")
		(30 "In14.Cu" signal "GND6")
		(32 "In15.Cu" signal "IN6")
		(34 "In16.Cu" signal "GND7")
		(2 "B.Cu" signal "BOTTOM")
		(9 "F.Adhes" user "F.Adhesive")
		(11 "B.Adhes" user "B.Adhesive")
		(13 "F.Paste" user "Package Geometry/Pastemask Top")
		(15 "B.Paste" user "Package Geometry/Pastemask Bottom")
		(5 "F.SilkS" user "Ref Des/Silkscreen Top")
		(7 "B.SilkS" user "Ref Des/Silkscreen Bottom")
		(1 "F.Mask" user "Board Geometry/Soldermask Top")
		(3 "B.Mask" user "Board Geometry/Soldermask Bottom")
		(17 "Dwgs.User" user "User.Drawings")
		(19 "Cmts.User" user "User.Comments")
		(21 "Eco1.User" user "User.Eco1")
		(23 "Eco2.User" user "User.Eco2")
		(25 "Edge.Cuts" user "Board Geometry/Outline")
		(27 "Margin" user)
		(31 "F.CrtYd" user "Package Geometry/Place Bound Top")
		(29 "B.CrtYd" user "Package Geometry/Place Bound Bottom")
		(35 "F.Fab" user "Ref Des/Assembly Top")
		(33 "B.Fab" user "Ref Des/Assembly Bottom")
	)
	(footprint ""
		(layer "F.Cu")
		(at 151.82977 -40.50792 180)
		(property "Reference" "R4463"
			(at 0 0 180)
			(layer "F.SilkS")
			(hide yes)
			(effects
				(font
					(size 1.27 1.27)
				)
			)
		)
		(property "Value" ""
			(at 0 0 180)
			(layer "F.Fab")
			(effects
				(font
					(size 1.27 1.27)
				)
			)
		)
		(duplicate_pad_numbers_are_jumpers no)
		(fp_line
			(start 0.7874 0.4064)
			(end -0.7874 0.4064)
			(stroke
				(width 0.1524)
				(type default)
			)
			(layer "F.SilkS")
		)
		(fp_line
			(start 0.7874 -0.4064)
			(end 0.7874 0.4064)
			(stroke
				(width 0.1524)
				(type default)
			)
			(layer "F.SilkS")
		)
		(fp_line
			(start -0.7874 0.4064)
			(end -0.7874 -0.4064)
			(stroke
				(width 0.1524)
				(type default)
			)
			(layer "F.SilkS")
		)
		(fp_line
			(start -0.7874 -0.4064)
			(end 0.7874 -0.4064)
			(stroke
				(width 0.1524)
				(type default)
			)
			(layer "F.SilkS")
		)
		(fp_line
			(start 0.67945 0.3048)
			(end 0.120396 0.3048)
			(stroke
				(width 0.1)
				(type default)
			)
			(layer "F.Fab")
		)
		(fp_line
			(start 0.67945 -0.3048)
			(end 0.67945 0.3048)
			(stroke
				(width 0.1)
				(type default)
			)
			(layer "F.Fab")
		)
		(fp_line
			(start 0.12065 -0.2794)
			(end 0.12065 -0.3048)
			(stroke
				(width 0.1)
				(type default)
			)
			(layer "F.Fab")
		)
		(fp_line
			(start 0.12065 -0.3048)
			(end 0.67945 -0.3048)
			(stroke
				(width 0.1)
				(type default)
			)
			(layer "F.Fab")
		)
		(fp_line
			(start 0.120396 0.3048)
			(end 0.120396 0.2794)
			(stroke
				(width 0.1)
				(type default)
			)
			(layer "F.Fab")
		)
		(fp_line
			(start 0.120396 0.2794)
			(end -0.12065 0.2794)
			(stroke
				(width 0.1)
				(type default)
			)
			(layer "F.Fab")
		)
		(fp_line
			(start -0.12065 0.3048)
			(end -0.67945 0.3048)
			(stroke
				(width 0.1)
				(type default)
			)
			(layer "F.Fab")
		)
		(fp_line
			(start -0.12065 0.2794)
			(end -0.12065 0.3048)
			(stroke
				(width 0.1)
				(type default)
			)
			(layer "F.Fab")
		)
		(fp_line
			(start -0.12065 -0.2794)
			(end 0.12065 -0.2794)
			(stroke
				(width 0.1)
				(type default)
			)
			(layer "F.Fab")
		)
		(fp_line
			(start -0.12065 -0.305054)
			(end -0.12065 -0.2794)
			(stroke
				(width 0.1)
				(type default)
			)
			(layer "F.Fab")
		)
		(fp_line
			(start -0.67945 0.3048)
			(end -0.67945 -0.305054)
			(stroke
				(width 0.1)
				(type default)
			)
			(layer "F.Fab")
		)
		(fp_line
			(start -0.67945 -0.305054)
			(end -0.12065 -0.305054)
			(stroke
				(width 0.1)
				(type default)
			)
			(layer "F.Fab")
		)
		(pad "1" smd circle
			(at -0.40005 0 180)
			(size 0 0)
			(layers "F.Cu" "F.Mask" "F.Paste")
			(net "USB_HUB_2_RREF")
		)
		(pad "2" smd circle
			(at 0.40005 0 180)
			(size 0 0)
			(layers "F.Cu" "F.Mask" "F.Paste")
			(net "GND")
		)
	)
	(footprint ""
		(layer "F.Cu")
		(at 144.61236 -92.634308 -90)
		(property "Reference" "R4051"
			(at 0 0 270)
			(layer "F.SilkS")
			(hide yes)
			(effects
				(font
					(size 1.27 1.27)
				)
			)
		)
		(property "Value" ""
			(at 0 0 270)
			(layer "F.Fab")
			(effects
				(font
					(size 1.27 1.27)
				)
			)
		)
		(duplicate_pad_numbers_are_jumpers no)
		(fp_line
			(start -0.7874 0.4064)
			(end -0.7874 -0.4064)
			(stroke
				(width 0.1524)
				(type default)
			)
			(layer "F.SilkS")
		)
		(fp_line
			(start 0.7874 0.4064)
			(end -0.7874 0.4064)
			(stroke
				(width 0.1524)
				(type default)
			)
			(layer "F.SilkS")
		)
		(fp_line
			(start -0.7874 -0.4064)
			(end 0.7874 -0.4064)
			(stroke
				(width 0.1524)
				(type default)
			)
			(layer "F.SilkS")
		)
		(fp_line
			(start 0.7874 -0.4064)
			(end 0.7874 0.4064)
			(stroke
				(width 0.1524)
				(type default)
			)
			(layer "F.SilkS")
		)
		(fp_line
			(start -0.67945 0.3048)
			(end -0.67945 -0.305054)
			(stroke
				(width 0.1)
				(type default)
			)
			(layer "F.Fab")
		)
		(fp_line
			(start -0.12065 0.3048)
			(end -0.67945 0.3048)
			(stroke
				(width 0.1)
				(type default)
			)
			(layer "F.Fab")
		)
		(fp_line
			(start 0.120396 0.3048)
			(end 0.120396 0.2794)
			(stroke
				(width 0.1)
				(type default)
			)
			(layer "F.Fab")
		)
		(fp_line
			(start 0.67945 0.3048)
			(end 0.120396 0.3048)
			(stroke
				(width 0.1)
				(type default)
			)
			(layer "F.Fab")
		)
		(fp_line
			(start -0.12065 0.2794)
			(end -0.12065 0.3048)
			(stroke
				(width 0.1)
				(type default)
			)
			(layer "F.Fab")
		)
		(fp_line
			(start 0.120396 0.2794)
			(end -0.12065 0.2794)
			(stroke
				(width 0.1)
				(type default)
			)
			(layer "F.Fab")
		)
		(fp_line
			(start -0.12065 -0.2794)
			(end 0.12065 -0.2794)
			(stroke
				(width 0.1)
				(type default)
			)
			(layer "F.Fab")
		)
		(fp_line
			(start 0.12065 -0.2794)
			(end 0.12065 -0.3048)
			(stroke
				(width 0.1)
				(type default)
			)
			(layer "F.Fab")
		)
		(fp_line
			(start 0.12065 -0.3048)
			(end 0.67945 -0.3048)
			(stroke
				(width 0.1)
				(type default)
			)
			(layer "F.Fab")
		)
		(fp_line
			(start 0.67945 -0.3048)
			(end 0.67945 0.3048)
			(stroke
				(width 0.1)
				(type default)
			)
			(layer "F.Fab")
		)
		(fp_line
			(start -0.67945 -0.305054)
			(end -0.12065 -0.305054)
			(stroke
				(width 0.1)
				(type default)
			)
			(layer "F.Fab")
		)
		(fp_line
			(start -0.12065 -0.305054)
			(end -0.12065 -0.2794)
			(stroke
				(width 0.1)
				(type default)
			)
			(layer "F.Fab")
		)
		(pad "1" smd circle
			(at -0.40005 0 270)
			(size 0 0)
			(layers "F.Cu" "F.Mask" "F.Paste")
			(net "H_CPU_ERR1_LVC2_R_N")
		)
		(pad "2" smd circle
			(at 0.40005 0 270)
			(size 0 0)
			(layers "F.Cu" "F.Mask" "F.Paste")
			(net "H_CPU_ERR1_LVC2_N")
		)
	)
)
